(kicad_pcb
	(version 20260206)
	(generator "pcbnew")
	(generator_version "10.0")
	(general
		(thickness 1.6)
		(legacy_teardrops no)
	)
	(paper "A4")
	(title_block
		(title "Bryce Canyon_R.DPB_16317-1_OCP.brd")
		(comment 1 "Bryce Canyon / footprints 188-194 of 2099")
	)
	(layers
		(0 "F.Cu" signal "TOP")
		(4 "In1.Cu" signal "L2GND")
		(6 "In2.Cu" signal "L3")
		(8 "In3.Cu" signal "L4VCC")
		(10 "In4.Cu" signal "L5VCC")
		(12 "In5.Cu" signal "L6")
		(14 "In6.Cu" signal "L7GND")
		(2 "B.Cu" signal "BOTTOM")
		(9 "F.Adhes" user "F.Adhesive")
		(11 "B.Adhes" user "B.Adhesive")
		(13 "F.Paste" user "Package Geometry/Pastemask Top")
		(15 "B.Paste" user "Package Geometry/Pastemask Bottom")
		(5 "F.SilkS" user "Ref Des/Silkscreen Top")
		(7 "B.SilkS" user "Ref Des/Silkscreen Bottom")
		(1 "F.Mask" user "Board Geometry/Soldermask Top")
		(3 "B.Mask" user "Board Geometry/Soldermask Bottom")
		(17 "Dwgs.User" user "User.Drawings")
		(19 "Cmts.User" user "User.Comments")
		(21 "Eco1.User" user "User.Eco1")
		(23 "Eco2.User" user "User.Eco2")
		(25 "Edge.Cuts" user "Board Geometry/Outline")
		(27 "Margin" user)
		(31 "F.CrtYd" user "Package Geometry/Place Bound Top")
		(29 "B.CrtYd" user "Package Geometry/Place Bound Bottom")
		(35 "F.Fab" user "Ref Des/Assembly Top")
		(33 "B.Fab" user "Ref Des/Assembly Bottom")
	)
	(footprint ""
		(layer "F.Cu")
		(at 48.514 -247.65 180)
		(property "Reference" "D1"
			(at 0 0 180)
			(layer "F.SilkS")
			(hide yes)
			(effects
				(font
					(size 1.27 1.27)
				)
			)
		)
		(property "Value" "RB551V30-GP"
			(at 0 -6.7818 180)
			(unlocked yes)
			(layer "F.Fab")
			(hide yes)
			(effects
				(font
					(size 1.016 1.016)
					(thickness 0.1524)
				)
			)
		)
		(property "Device Type" "SOD323AKH38"
			(at 0 -8.6868 180)
			(unlocked yes)
			(layer "F.Fab")
			(hide yes)
			(effects
				(font
					(size 1.016 1.016)
					(thickness 0.1524)
				)
			)
		)
		(duplicate_pad_numbers_are_jumpers no)
		(fp_line
			(start 0.889 2.159)
			(end -0.889 2.159)
			(stroke
				(width 0.1524)
				(type default)
			)
			(layer "F.SilkS")
		)
		(fp_line
			(start 0.889 -1.9304)
			(end 0.889 2.159)
			(stroke
				(width 0.1524)
				(type default)
			)
			(layer "F.SilkS")
		)
		(fp_line
			(start 0.762 2.0574)
			(end -0.762 2.0574)
			(stroke
				(width 0.508)
				(type default)
			)
			(layer "F.SilkS")
		)
		(fp_line
			(start -0.889 2.159)
			(end -0.889 -1.9304)
			(stroke
				(width 0.1524)
				(type default)
			)
			(layer "F.SilkS")
		)
		(fp_line
			(start -0.889 -1.9304)
			(end 0.889 -1.9304)
			(stroke
				(width 0.1524)
				(type default)
			)
			(layer "F.SilkS")
		)
		(fp_rect
			(start -1.016 2.3114)
			(end 1.016 -2.0066)
			(stroke
				(width 0)
				(type default)
			)
			(fill no)
			(layer "F.CrtYd")
		)
		(fp_poly
			(pts
				(xy -1.016 -2.0066) (xy 1.016 -2.0066) (xy 1.016 2.3114) (xy -1.016 2.3114)
			)
			(stroke
				(width 0)
				(type default)
			)
			(fill no)
			(layer "F.Fab")
		)
		(pad "A" smd rect
			(at 0 -1.143 180)
			(size 0.5588 1.016)
			(layers "F.Cu" "F.Mask" "F.Paste")
			(net "SW_HDD_R1")
		)
		(pad "K" smd rect
			(at 0 1.143 180)
			(size 0.5588 1.016)
			(layers "F.Cu" "F.Mask" "F.Paste")
			(net "SW_HDD_N1")
		)
	)
	(footprint ""
		(layer "F.Cu")
		(at 440.69 -99.187)
		(property "Reference" "R456"
			(at 0 0 0)
			(layer "F.SilkS")
			(hide yes)
			(effects
				(font
					(size 1.27 1.27)
				)
			)
		)
		(property "Value" "130R3F-GP"
			(at -0.0254 -2.5146 0)
			(unlocked yes)
			(layer "F.Fab")
			(hide yes)
			(effects
				(font
					(size 1.016 1.016)
					(thickness 0.1524)
				)
			)
		)
		(property "Device Type" "R603H22"
			(at -0.0254 -4.0386 0)
			(unlocked yes)
			(layer "F.Fab")
			(hide yes)
			(effects
				(font
					(size 1.016 1.016)
					(thickness 0.1524)
				)
			)
		)
		(duplicate_pad_numbers_are_jumpers no)
		(fp_line
			(start -0.4826 0)
			(end -0.2032 0)
			(stroke
				(width 0.2032)
				(type default)
			)
			(layer "F.SilkS")
		)
		(fp_line
			(start 0.2032 0)
			(end 0.4826 0)
			(stroke
				(width 0.2032)
				(type default)
			)
			(layer "F.SilkS")
		)
		(fp_rect
			(start -0.5842 1.3335)
			(end 0.5842 -1.3335)
			(stroke
				(width 0)
				(type default)
			)
			(fill no)
			(layer "F.CrtYd")
		)
		(fp_rect
			(start -0.5842 1.3335)
			(end 0.5842 -1.3335)
			(stroke
				(width 0)
				(type default)
			)
			(fill no)
			(layer "F.Fab")
		)
		(pad "1" smd custom
			(at 0 -0.762)
			(size 0.2159 0.2159)
			(layers "F.Cu" "F.Mask" "F.Paste")
			(net "P5V_B_4")
			(options
				(clearance outline)
				(anchor circle)
			)
			(primitives
				(gr_poly
					(pts
						(arc
							(start -0.3302 -0.4318)
							(mid -0.402042 -0.402042)
							(end -0.4318 -0.3302)
						)
						(arc
							(start -0.4318 0.3302)
							(mid -0.402042 0.402042)
							(end -0.3302 0.4318)
						)
						(arc
							(start 0.3302 0.4318)
							(mid 0.402042 0.402042)
							(end 0.4318 0.3302)
						)
						(arc
							(start 0.4318 -0.3302)
							(mid 0.402042 -0.402042)
							(end 0.3302 -0.4318)
						)
					)
					(width 0)
					(fill yes)
				)
			)
		)
		(pad "2" smd custom
			(at 0 0.762)
			(size 0.2159 0.2159)
			(layers "F.Cu" "F.Mask" "F.Paste")
			(net "FLT_HDD22")
			(options
				(clearance outline)
				(anchor circle)
			)
			(primitives
				(gr_poly
					(pts
						(arc
							(start -0.3302 -0.4318)
							(mid -0.402042 -0.402042)
							(end -0.4318 -0.3302)
						)
						(arc
							(start -0.4318 0.3302)
							(mid -0.402042 0.402042)
							(end -0.3302 0.4318)
						)
						(arc
							(start 0.3302 0.4318)
							(mid 0.402042 0.402042)
							(end 0.4318 0.3302)
						)
						(arc
							(start 0.4318 -0.3302)
							(mid 0.402042 -0.402042)
							(end 0.3302 -0.4318)
						)
					)
					(width 0)
					(fill yes)
				)
			)
		)
	)
	(footprint ""
		(layer "F.Cu")
		(at 214.24773 -353.792536 90)
		(property "Reference" "R152"
			(at 0 0 90)
			(layer "F.SilkS")
			(hide yes)
			(effects
				(font
					(size 1.27 1.27)
				)
			)
		)
		(property "Value" "0R5J-5-GP"
			(at 0 -8.9535 90)
			(unlocked yes)
			(layer "F.Fab")
			(hide yes)
			(effects
				(font
					(size 1.27 1.016)
					(thickness 0.1524)
				)
			)
		)
		(property "Device Type" "R805H24"
			(at 0 -10.6299 90)
			(unlocked yes)
			(layer "F.Fab")
			(hide yes)
			(effects
				(font
					(size 1.27 1.016)
					(thickness 0.1524)
				)
			)
		)
		(duplicate_pad_numbers_are_jumpers no)
		(fp_line
			(start 0.889 -1.7018)
			(end -0.889 -1.7018)
			(stroke
				(width 0.1524)
				(type default)
			)
			(layer "F.SilkS")
		)
		(fp_line
			(start 0.889 -1.7018)
			(end 0.889 -0.381)
			(stroke
				(width 0.1524)
				(type default)
			)
			(layer "F.SilkS")
		)
		(fp_line
			(start -0.889 -1.7018)
			(end -0.889 0.2794)
			(stroke
				(width 0.1524)
				(type default)
			)
			(layer "F.SilkS")
		)
		(fp_line
			(start -0.889 0.0762)
			(end -0.889 1.7018)
			(stroke
				(width 0.1524)
				(type default)
			)
			(layer "F.SilkS")
		)
		(fp_line
			(start 0.889 1.7018)
			(end 0.889 -0.508)
			(stroke
				(width 0.1524)
				(type default)
			)
			(layer "F.SilkS")
		)
		(fp_line
			(start -0.889 1.7018)
			(end 0.889 1.7018)
			(stroke
				(width 0.1524)
				(type default)
			)
			(layer "F.SilkS")
		)
		(fp_poly
			(pts
				(xy 0.9652 -1.778) (xy 0.9652 1.778) (xy -0.9652 1.778) (xy -0.9652 -1.778)
			)
			(stroke
				(width 0)
				(type default)
			)
			(fill no)
			(layer "F.CrtYd")
		)
		(fp_rect
			(start -0.9652 1.778)
			(end 0.9652 -1.778)
			(stroke
				(width 0)
				(type default)
			)
			(fill no)
			(layer "F.Fab")
		)
		(pad "1" smd rect
			(at 0 -0.9652 90)
			(size 1.397 1.143)
			(layers "F.Cu" "F.Mask" "F.Paste")
			(net "MB0_CM_GATE_R")
		)
		(pad "2" smd rect
			(at 0 0.9652 90)
			(size 1.397 1.143)
			(layers "F.Cu" "F.Mask" "F.Paste")
			(net "MB0_CM_GATE_C")
		)
	)
	(footprint ""
		(layer "F.Cu")
		(at 392.938 -152.908 180)
		(property "Reference" "C290"
			(at 0 0 180)
			(layer "F.SilkS")
			(hide yes)
			(effects
				(font
					(size 1.27 1.27)
				)
			)
		)
		(property "Value" "SC1U16V3KX-5GP"
			(at 0 -2.8194 180)
			(unlocked yes)
			(layer "F.Fab")
			(hide yes)
			(effects
				(font
					(size 1.016 1.016)
					(thickness 0.1524)
				)
			)
		)
		(property "Device Type" "C603H36"
			(at 0 -4.3434 180)
			(unlocked yes)
			(layer "F.Fab")
			(hide yes)
			(effects
				(font
					(size 1.016 1.016)
					(thickness 0.1524)
				)
			)
		)
		(duplicate_pad_numbers_are_jumpers no)
		(fp_line
			(start 0.508 0)
			(end -0.508 0)
			(stroke
				(width 0.2032)
				(type default)
			)
			(layer "F.SilkS")
		)
		(fp_rect
			(start -0.5842 1.3335)
			(end 0.5842 -1.3335)
			(stroke
				(width 0)
				(type default)
			)
			(fill no)
			(layer "F.CrtYd")
		)
		(fp_rect
			(start -0.5842 1.3335)
			(end 0.5842 -1.3335)
			(stroke
				(width 0)
				(type default)
			)
			(fill no)
			(layer "F.Fab")
		)
		(pad "1" smd custom
			(at 0 -0.762 180)
			(size 0.2159 0.2159)
			(layers "F.Cu" "F.Mask" "F.Paste")
			(net "P5V_HDD20")
			(options
				(clearance outline)
				(anchor circle)
			)
			(primitives
				(gr_poly
					(pts
						(arc
							(start -0.3302 -0.4318)
							(mid -0.402042 -0.402042)
							(end -0.4318 -0.3302)
						)
						(arc
							(start -0.4318 0.3302)
							(mid -0.402042 0.402042)
							(end -0.3302 0.4318)
						)
						(arc
							(start 0.3302 0.4318)
							(mid 0.402042 0.402042)
							(end 0.4318 0.3302)
						)
						(arc
							(start 0.4318 -0.3302)
							(mid 0.402042 -0.402042)
							(end 0.3302 -0.4318)
						)
					)
					(width 0)
					(fill yes)
				)
			)
		)
		(pad "2" smd custom
			(at 0 0.762 180)
			(size 0.2159 0.2159)
			(layers "F.Cu" "F.Mask" "F.Paste")
			(net "GND")
			(options
				(clearance outline)
				(anchor circle)
			)
			(primitives
				(gr_poly
					(pts
						(arc
							(start -0.3302 -0.4318)
							(mid -0.402042 -0.402042)
							(end -0.4318 -0.3302)
						)
						(arc
							(start -0.4318 0.3302)
							(mid -0.402042 0.402042)
							(end -0.3302 0.4318)
						)
						(arc
							(start 0.3302 0.4318)
							(mid 0.402042 0.402042)
							(end 0.4318 0.3302)
						)
						(arc
							(start 0.4318 -0.3302)
							(mid 0.402042 -0.402042)
							(end 0.3302 -0.4318)
						)
					)
					(width 0)
					(fill yes)
				)
			)
		)
	)
	(footprint ""
		(layer "F.Cu")
		(at 369.57 -20.447 90)
		(property "Reference" "R799"
			(at 0 0 90)
			(layer "F.SilkS")
			(hide yes)
			(effects
				(font
					(size 1.27 1.27)
				)
			)
		)
		(property "Value" "200KR2F-L-GP"
			(at 0.064008 -3.993896 90)
			(unlocked yes)
			(layer "F.Fab")
			(hide yes)
			(effects
				(font
					(size 1.016 1.016)
					(thickness 0.1524)
				)
			)
		)
		(property "Device Type" "R402H16"
			(at 0.064008 -5.517896 90)
			(unlocked yes)
			(layer "F.Fab")
			(hide yes)
			(effects
				(font
					(size 1.016 1.016)
					(thickness 0.1524)
				)
			)
		)
		(duplicate_pad_numbers_are_jumpers no)
		(fp_line
			(start 0.508 -0.9398)
			(end -0.508 -0.9398)
			(stroke
				(width 0.1524)
				(type default)
			)
			(layer "F.SilkS")
		)
		(fp_line
			(start -0.508 -0.9398)
			(end -0.508 0.9398)
			(stroke
				(width 0.1524)
				(type default)
			)
			(layer "F.SilkS")
		)
		(fp_rect
			(start -0.508 0.9398)
			(end 0.508 -0.9398)
			(stroke
				(width 0)
				(type default)
			)
			(fill no)
			(layer "F.CrtYd")
		)
		(fp_rect
			(start -0.508 0.9398)
			(end 0.508 -0.9398)
			(stroke
				(width 0)
				(type default)
			)
			(fill no)
			(layer "F.Fab")
		)
		(pad "1" smd custom
			(at 0 -0.4445 90)
			(size 0.1397 0.1397)
			(layers "F.Cu" "F.Mask" "F.Paste")
			(net "SW_HDD_R31")
			(options
				(clearance outline)
				(anchor circle)
			)
			(primitives
				(gr_poly
					(pts
						(arc
							(start -0.1778 -0.2794)
							(mid -0.249642 -0.249642)
							(end -0.2794 -0.1778)
						)
						(arc
							(start -0.2794 0.1778)
							(mid -0.249642 0.249642)
							(end -0.1778 0.2794)
						)
						(arc
							(start 0.1778 0.2794)
							(mid 0.249642 0.249642)
							(end 0.2794 0.1778)
						)
						(arc
							(start 0.2794 -0.1778)
							(mid 0.249642 -0.249642)
							(end 0.1778 -0.2794)
						)
					)
					(width 0)
					(fill yes)
				)
			)
		)
		(pad "2" smd custom
			(at 0 0.4445 90)
			(size 0.1397 0.1397)
			(layers "F.Cu" "F.Mask" "F.Paste")
			(net "SW_HDD_N31")
			(options
				(clearance outline)
				(anchor circle)
			)
			(primitives
				(gr_poly
					(pts
						(arc
							(start -0.1778 -0.2794)
							(mid -0.249642 -0.249642)
							(end -0.2794 -0.1778)
						)
						(arc
							(start -0.2794 0.1778)
							(mid -0.249642 0.249642)
							(end -0.1778 0.2794)
						)
						(arc
							(start 0.1778 0.2794)
							(mid 0.249642 0.249642)
							(end 0.2794 0.1778)
						)
						(arc
							(start 0.2794 -0.1778)
							(mid 0.249642 -0.249642)
							(end 0.1778 -0.2794)
						)
					)
					(width 0)
					(fill yes)
				)
			)
		)
	)
	(footprint ""
		(layer "F.Cu")
		(at 343.993978 -217.413586 -90)
		(property "Reference" "R258"
			(at 0 0 270)
			(layer "F.SilkS")
			(hide yes)
			(effects
				(font
					(size 1.27 1.27)
				)
			)
		)
		(property "Value" "4K7R2F-GP"
			(at 0.064008 -3.993896 270)
			(unlocked yes)
			(layer "F.Fab")
			(hide yes)
			(effects
				(font
					(size 1.016 1.016)
					(thickness 0.1524)
				)
			)
		)
		(property "Device Type" "R402H16"
			(at 0.064008 -5.517896 270)
			(unlocked yes)
			(layer "F.Fab")
			(hide yes)
			(effects
				(font
					(size 1.016 1.016)
					(thickness 0.1524)
				)
			)
		)
		(duplicate_pad_numbers_are_jumpers no)
		(fp_line
			(start -0.508 -0.9398)
			(end -0.508 0.9398)
			(stroke
				(width 0.1524)
				(type default)
			)
			(layer "F.SilkS")
		)
		(fp_line
			(start 0.508 -0.9398)
			(end -0.508 -0.9398)
			(stroke
				(width 0.1524)
				(type default)
			)
			(layer "F.SilkS")
		)
		(fp_rect
			(start -0.508 0.9398)
			(end 0.508 -0.9398)
			(stroke
				(width 0)
				(type default)
			)
			(fill no)
			(layer "F.CrtYd")
		)
		(fp_rect
			(start -0.508 0.9398)
			(end 0.508 -0.9398)
			(stroke
				(width 0)
				(type default)
			)
			(fill no)
			(layer "F.Fab")
		)
		(pad "1" smd custom
			(at 0 -0.4445 270)
			(size 0.1397 0.1397)
			(layers "F.Cu" "F.Mask" "F.Paste")
			(net "DRIVE_B_7_FLT_LED")
			(options
				(clearance outline)
				(anchor circle)
			)
			(primitives
				(gr_poly
					(pts
						(arc
							(start -0.1778 -0.2794)
							(mid -0.249642 -0.249642)
							(end -0.2794 -0.1778)
						)
						(arc
							(start -0.2794 0.1778)
							(mid -0.249642 0.249642)
							(end -0.1778 0.2794)
						)
						(arc
							(start 0.1778 0.2794)
							(mid 0.249642 0.249642)
							(end 0.2794 0.1778)
						)
						(arc
							(start 0.2794 -0.1778)
							(mid 0.249642 -0.249642)
							(end 0.1778 -0.2794)
						)
					)
					(width 0)
					(fill yes)
				)
			)
		)
		(pad "2" smd custom
			(at 0 0.4445 270)
			(size 0.1397 0.1397)
			(layers "F.Cu" "F.Mask" "F.Paste")
			(net "GND")
			(options
				(clearance outline)
				(anchor circle)
			)
			(primitives
				(gr_poly
					(pts
						(arc
							(start -0.1778 -0.2794)
							(mid -0.249642 -0.249642)
							(end -0.2794 -0.1778)
						)
						(arc
							(start -0.2794 0.1778)
							(mid -0.249642 0.249642)
							(end -0.1778 0.2794)
						)
						(arc
							(start 0.1778 0.2794)
							(mid 0.249642 0.249642)
							(end 0.2794 0.1778)
						)
						(arc
							(start 0.2794 -0.1778)
							(mid 0.249642 -0.249642)
							(end 0.1778 -0.2794)
						)
					)
					(width 0)
					(fill yes)
				)
			)
		)
	)
	(footprint ""
		(layer "F.Cu")
		(at 20.447 -134.493 180)
		(property "Reference" "Q47"
			(at 0 0 180)
			(layer "F.SilkS")
			(hide yes)
			(effects
				(font
					(size 1.27 1.27)
				)
			)
		)
		(property "Value" "2N7002KDW-GP"
			(at -2.3622 -8.2042 180)
			(unlocked yes)
			(layer "F.Fab")
			(hide yes)
			(effects
				(font
					(size 1.016 1.016)
					(thickness 0.1524)
				)
			)
		)
		(property "Device Type" "SOT-363H44"
			(at -2.3622 -10.1092 180)
			(unlocked yes)
			(layer "F.Fab")
			(hide yes)
			(effects
				(font
					(size 1.016 1.016)
					(thickness 0.1524)
				)
			)
		)
		(duplicate_pad_numbers_are_jumpers no)
		(fp_line
			(start 1.4478 1.7018)
			(end 1.4478 -1.7018)
			(stroke
				(width 0.1524)
				(type default)
			)
			(layer "F.SilkS")
		)
		(fp_line
			(start 1.4478 -1.7018)
			(end -1.4478 -1.7018)
			(stroke
				(width 0.1524)
				(type default)
			)
			(layer "F.SilkS")
		)
		(fp_line
			(start -1.27 1.524)
			(end -1.27 0.6604)
			(stroke
				(width 0.4826)
				(type default)
			)
			(layer "F.SilkS")
		)
		(fp_line
			(start -1.4478 1.7018)
			(end 1.4478 1.7018)
			(stroke
				(width 0.1524)
				(type default)
			)
			(layer "F.SilkS")
		)
		(fp_line
			(start -1.4478 -1.7018)
			(end -1.4478 1.7018)
			(stroke
				(width 0.1524)
				(type default)
			)
			(layer "F.SilkS")
		)
		(fp_poly
			(pts
				(xy -1.524 -1.778) (xy 1.524 -1.778) (xy 1.524 1.778) (xy -1.524 1.778)
			)
			(stroke
				(width 0)
				(type default)
			)
			(fill no)
			(layer "F.CrtYd")
		)
		(fp_poly
			(pts
				(xy -1.524 -1.778) (xy 1.524 -1.778) (xy 1.524 1.778) (xy -1.524 1.778)
			)
			(stroke
				(width 0)
				(type default)
			)
			(fill no)
			(layer "F.Fab")
		)
		(pad "1" smd rect
			(at -0.65024 0.9398 180)
			(size 0.4064 1.016)
			(layers "F.Cu" "F.Mask" "F.Paste")
			(net "GND")
		)
		(pad "2" smd rect
			(at 0 0.9398 180)
			(size 0.4064 1.016)
			(layers "F.Cu" "F.Mask" "F.Paste")
			(net "SW_PWR_R_HDD12")
		)
		(pad "3" smd rect
			(at 0.65024 0.9398 180)
			(size 0.4064 1.016)
			(layers "F.Cu" "F.Mask" "F.Paste")
			(net "SW_HDD_P12")
		)
		(pad "4" smd rect
			(at 0.65024 -0.9398 180)
			(size 0.4064 1.016)
			(layers "F.Cu" "F.Mask" "F.Paste")
			(net "GND")
		)
		(pad "5" smd rect
			(at 0 -0.9398 180)
			(size 0.4064 1.016)
			(layers "F.Cu" "F.Mask" "F.Paste")
			(net "SW_HDD_G12")
		)
		(pad "6" smd rect
			(at -0.65024 -0.9398 180)
			(size 0.4064 1.016)
			(layers "F.Cu" "F.Mask" "F.Paste")
			(net "SW_HDD_R12")
		)
	)
)
